# TIMECARD (Time Appliance Project (Time Card)) — schematic netlist excerpt (pin names and nets, part order shuffled) for the footprints in the layout excerpt that follows; sources: Cadence DE-HDL packaged netlist, KiCad conversion of R4006-B0001-02_R01.brd

TP11  TP_PIONT  pkg TP010CT020B030_PTH  page 25 : \1\ = FT_USB_DETECT
TP4  TP_PIONT  pkg TP010CT020B030_PTH  page 25 : \1\ = XP5R0V_FT4232
R360  RESISTOR  10KOHM 1%  pkg SMC_0402R_H016  page 13 : \1\ = MHZ200CLKN_CLKIN ; \2\ = SG

(kicad_pcb
	(version 20260206)
	(generator "pcbnew")
	(generator_version "10.0")
	(general
		(thickness 1.6)
		(legacy_teardrops no)
	)
	(paper "A4")
	(title_block
		(title "timecard-production-celestica-r4006 — R4006-B0001-02_R01.brd")
		(comment 1 "Time Appliance Project (Time Card) / footprints 390-392 of 1113")
	)
	(layers
		(0 "F.Cu" signal "TOP")
		(4 "In1.Cu" signal "L02_GND1")
		(6 "In2.Cu" signal "L03_SIG1")
		(8 "In3.Cu" signal "L04_GND2")
		(10 "In4.Cu" signal "L05_VCC1")
		(12 "In5.Cu" signal "L06_VCC2")
		(14 "In6.Cu" signal "L07_GND3")
		(16 "In7.Cu" signal "L08_SIG2")
		(18 "In8.Cu" signal "L09_GND4")
		(2 "B.Cu" signal "BOTTOM")
		(9 "F.Adhes" user "F.Adhesive")
		(11 "B.Adhes" user "B.Adhesive")
		(13 "F.Paste" user "Package Geometry/Pastemask Top")
		(15 "B.Paste" user "Package Geometry/Pastemask Bottom")
		(5 "F.SilkS" user "Ref Des/Silkscreen Top")
		(7 "B.SilkS" user "Ref Des/Silkscreen Bottom")
		(1 "F.Mask" user "Board Geometry/Soldermask Top")
		(3 "B.Mask" user "Board Geometry/Soldermask Bottom")
		(17 "Dwgs.User" user "User.Drawings")
		(19 "Cmts.User" user "User.Comments")
		(21 "Eco1.User" user "User.Eco1")
		(23 "Eco2.User" user "User.Eco2")
		(25 "Edge.Cuts" user "Board Geometry/Outline")
		(27 "Margin" user)
		(31 "F.CrtYd" user "Package Geometry/Place Bound Top")
		(29 "B.CrtYd" user "Package Geometry/Place Bound Bottom")
		(35 "F.Fab" user "Ref Des/Assembly Top")
		(33 "B.Fab" user "Ref Des/Assembly Bottom")
	)
	(footprint ""
		(layer "F.Cu")
		(at 110.3757 -28.5242 180)
		(property "Reference" "R360"
			(at 2.00533 -0.8382 90)
			(unlocked yes)
			(layer "F.SilkS")
			(effects
				(font
					(size 0.7874 0.5842)
					(thickness 0.1524)
				)
			)
		)
		(property "Value" "VAL*"
			(at 0.02032 2.13233 180)
			(unlocked yes)
			(layer "F.Fab")
			(hide yes)
			(effects
				(font
					(size 0.7874 0.5842)
					(thickness 0.1524)
				)
			)
		)
		(property "Tolerance" "TOL*"
			(at 0.044704 3.05435 180)
			(unlocked yes)
			(layer "Cmts.User")
			(hide yes)
			(effects
				(font
					(size 0.7874 0.5842)
					(thickness 0.1524)
				)
			)
		)
		(property "User Part Number" "PARTNUM*"
			(at 0.02032 4.024884 180)
			(unlocked yes)
			(layer "Cmts.User")
			(hide yes)
			(effects
				(font
					(size 0.7874 0.5842)
					(thickness 0.1524)
				)
			)
		)
		(property "Device Type" "RESISTOR-G155-11002-01,10KOHM,A"
			(at 0.008382 1.210564 180)
			(unlocked yes)
			(layer "F.Fab")
			(hide yes)
			(effects
				(font
					(size 0.7874 0.5842)
					(thickness 0.1524)
				)
			)
		)
		(duplicate_pad_numbers_are_jumpers no)
		(fp_line
			(start 1.143 0.5588)
			(end 1.143 -0.5588)
			(stroke
				(width 0.1)
				(type default)
			)
			(layer "F.SilkS")
		)
		(fp_line
			(start 1.143 -0.5588)
			(end -1.143 -0.5588)
			(stroke
				(width 0.1)
				(type default)
			)
			(layer "F.SilkS")
		)
		(fp_line
			(start -1.143 0.5588)
			(end 1.143 0.5588)
			(stroke
				(width 0.1)
				(type default)
			)
			(layer "F.SilkS")
		)
		(fp_line
			(start -1.143 -0.5588)
			(end -1.143 0.5588)
			(stroke
				(width 0.1)
				(type default)
			)
			(layer "F.SilkS")
		)
		(fp_poly
			(pts
				(xy -1.143 0.5588) (xy 1.143 0.5588) (xy 1.143 -0.5588) (xy -1.143 -0.5588)
			)
			(stroke
				(width 0)
				(type default)
			)
			(fill no)
			(layer "F.CrtYd")
		)
		(fp_line
			(start 0.508 0.3048)
			(end 0.508 -0.3048)
			(stroke
				(width 0.1)
				(type default)
			)
			(layer "F.Fab")
		)
		(fp_line
			(start 0.508 -0.3048)
			(end -0.508 -0.3048)
			(stroke
				(width 0.1)
				(type default)
			)
			(layer "F.Fab")
		)
		(fp_line
			(start -0.508 0.3048)
			(end 0.508 0.3048)
			(stroke
				(width 0.1)
				(type default)
			)
			(layer "F.Fab")
		)
		(fp_line
			(start -0.508 -0.3048)
			(end -0.508 0.3048)
			(stroke
				(width 0.1)
				(type default)
			)
			(layer "F.Fab")
		)
		(pad "1" smd rect
			(at -0.5334 0 180)
			(size 0.7112 0.6096)
			(layers "F.Cu" "F.Mask" "F.Paste")
			(net "MHZ200CLKN_CLKIN")
		)
		(pad "2" smd rect
			(at 0.5334 0 180)
			(size 0.7112 0.6096)
			(layers "F.Cu" "F.Mask" "F.Paste")
			(net "SG")
		)
		(zone
			(layer "F.Cu")
			(hatch none 0.5)
			(connect_pads
				(clearance 0)
			)
			(min_thickness 0.25)
			(keepout
				(tracks not_allowed)
				(vias allowed)
				(pads allowed)
				(copperpour not_allowed)
				(footprints allowed)
			)
			(placement
				(enabled no)
				(sheetname "")
			)
			(fill
				(thermal_gap 0.5)
				(thermal_bridge_width 0.5)
				(island_removal_mode 0)
			)
			(polygon
				(pts
					(xy 110.4519 -28.829) (xy 110.2995 -28.829) (xy 110.2995 -28.2194) (xy 110.4519 -28.2194)
				)
			)
		)
		(zone
			(layer "F.Cu")
			(hatch none 0.5)
			(connect_pads
				(clearance 0)
			)
			(min_thickness 0.25)
			(keepout
				(tracks allowed)
				(vias not_allowed)
				(pads allowed)
				(copperpour not_allowed)
				(footprints allowed)
			)
			(placement
				(enabled no)
				(sheetname "")
			)
			(fill
				(thermal_gap 0.5)
				(thermal_bridge_width 0.5)
				(island_removal_mode 0)
			)
			(polygon
				(pts
					(xy 110.4519 -28.829) (xy 110.2995 -28.829) (xy 110.2995 -28.2194) (xy 110.4519 -28.2194)
				)
			)
		)
	)
	(footprint ""
		(layer "F.Cu")
		(at 18.034 -83.947 -90)
		(property "Reference" "TP4"
			(at 0 0 270)
			(layer "F.SilkS")
			(hide yes)
			(effects
				(font
					(size 1.27 1.27)
				)
			)
		)
		(property "Value" ""
			(at 0 0 270)
			(layer "F.Fab")
			(effects
				(font
					(size 1.27 1.27)
				)
			)
		)
		(property "Device Type" "TP_PIONT-TP010CT020B030_PTH-TPA"
			(at -1.341882 0.996696 270)
			(unlocked yes)
			(layer "F.Fab")
			(hide yes)
			(effects
				(font
					(size 0.7874 0.5842)
					(thickness 0.1524)
				)
				(justify left)
			)
		)
		(duplicate_pad_numbers_are_jumpers no)
		(fp_poly
			(pts
				(arc
					(start 0 -0.889)
					(mid 0 0.889)
					(end 0 -0.889)
				)
			)
			(stroke
				(width 0)
				(type default)
			)
			(fill no)
			(layer "B.CrtYd")
		)
		(fp_poly
			(pts
				(arc
					(start 0 -0.889)
					(mid 0 0.889)
					(end 0 -0.889)
				)
			)
			(stroke
				(width 0)
				(type default)
			)
			(fill no)
			(layer "F.CrtYd")
		)
		(pad "1" thru_hole circle
			(at 0 0 270)
			(size 0.508 0.508)
			(drill 0.254)
			(layers "*.Cu" "*.Mask")
			(remove_unused_layers no)
			(net "XP5R0V_FT4232")
			(clearance 0.1016)
			(padstack
				(mode front_inner_back)
				(layer "Inner"
					(shape circle)
					(size 0.508 0.508)
					(clearance 0.1016)
				)
				(layer "B.Cu"
					(shape circle)
					(size 0.762 0.762)
					(clearance -0.0254)
				)
			)
		)
	)
	(footprint ""
		(layer "F.Cu")
		(at 25.273 -93.98)
		(property "Reference" "TP11"
			(at -0.08763 -0.8128 90)
			(unlocked yes)
			(layer "F.SilkS")
			(effects
				(font
					(size 0.7874 0.5842)
					(thickness 0.1524)
				)
				(justify left)
			)
		)
		(property "Value" ""
			(at 0 0 0)
			(layer "F.Fab")
			(effects
				(font
					(size 1.27 1.27)
				)
			)
		)
		(property "Device Type" "TP_PIONT-TP010CT020B030_PTH-TPA"
			(at -1.341882 0.996696 0)
			(unlocked yes)
			(layer "F.Fab")
			(hide yes)
			(effects
				(font
					(size 0.7874 0.5842)
					(thickness 0.000001)
				)
				(justify left)
			)
		)
		(duplicate_pad_numbers_are_jumpers no)
		(fp_poly
			(pts
				(arc
					(start 0.889 0)
					(mid -0.889 0)
					(end 0.889 0)
				)
			)
			(stroke
				(width 0)
				(type default)
			)
			(fill no)
			(layer "B.CrtYd")
		)
		(fp_poly
			(pts
				(arc
					(start 0.889 0)
					(mid -0.889 0)
					(end 0.889 0)
				)
			)
			(stroke
				(width 0)
				(type default)
			)
			(fill no)
			(layer "F.CrtYd")
		)
		(pad "1" thru_hole circle
			(at 0 0)
			(size 0.508 0.508)
			(drill 0.254)
			(layers "*.Cu" "*.Mask")
			(remove_unused_layers no)
			(net "FT_USB_DETECT")
			(clearance 0.1016)
			(padstack
				(mode front_inner_back)
				(layer "Inner"
					(shape circle)
					(size 0.508 0.508)
					(clearance 0.1016)
				)
				(layer "B.Cu"
					(shape circle)
					(size 0.762 0.762)
					(clearance -0.0254)
				)
			)
		)
	)
)
